# BASEBOARD_FAB2 (Tioga Pass) — schematic netlist excerpt (pin names and nets, part order shuffled) for the footprints in the layout excerpt that follows; sources: Cadence DE-HDL packaged netlist, KiCad conversion of Wiwynn_Tioga_Pass_MB.brd

R1B10  RES  0.0 5% CHIP  pkg 0402  page 226 : A = SVID_VDIO_PVDDQ_KLM ; B = SVID_DIO1_CPU1_R
RT2  1R3F-GP  1%  pkg RCL_GP  page 202 : \1\ = VR_PVCCIN_CPU0_PHASE1_RC ; \2\ = GND
C5A8  CAP_A  47UF 4V 20% X5R  pkg 0603V  page 220 : A = PVDDQ_DEF ; B = GND

(kicad_pcb
	(version 20260206)
	(generator "pcbnew")
	(generator_version "10.0")
	(general
		(thickness 1.6)
		(legacy_teardrops no)
	)
	(paper "A4")
	(title_block
		(title "Wiwynn_Tioga_Pass_MB.brd")
		(comment 1 "Tioga Pass / footprints 281-283 of 4770")
	)
	(layers
		(0 "F.Cu" signal "TOP")
		(4 "In1.Cu" signal "L2GND")
		(6 "In2.Cu" signal "L3")
		(8 "In3.Cu" signal "L4GND")
		(10 "In4.Cu" signal "L5")
		(12 "In5.Cu" signal "L6GND")
		(14 "In6.Cu" signal "L7VCC")
		(16 "In7.Cu" signal "L8VCC")
		(18 "In8.Cu" signal "L9GND")
		(20 "In9.Cu" signal "L10")
		(22 "In10.Cu" signal "L11GND")
		(24 "In11.Cu" signal "L12")
		(26 "In12.Cu" signal "L13GND")
		(2 "B.Cu" signal "BOTTOM")
		(9 "F.Adhes" user "F.Adhesive")
		(11 "B.Adhes" user "B.Adhesive")
		(13 "F.Paste" user "Package Geometry/Pastemask Top")
		(15 "B.Paste" user "Package Geometry/Pastemask Bottom")
		(5 "F.SilkS" user "Ref Des/Silkscreen Top")
		(7 "B.SilkS" user "Ref Des/Silkscreen Bottom")
		(1 "F.Mask" user "Board Geometry/Soldermask Top")
		(3 "B.Mask" user "Board Geometry/Soldermask Bottom")
		(17 "Dwgs.User" user "User.Drawings")
		(19 "Cmts.User" user "User.Comments")
		(21 "Eco1.User" user "User.Eco1")
		(23 "Eco2.User" user "User.Eco2")
		(25 "Edge.Cuts" user "Board Geometry/Outline")
		(27 "Margin" user)
		(31 "F.CrtYd" user "Package Geometry/Place Bound Top")
		(29 "B.CrtYd" user "Package Geometry/Place Bound Bottom")
		(35 "F.Fab" user "Ref Des/Assembly Top")
		(33 "B.Fab" user "Ref Des/Assembly Bottom")
	)
	(footprint ""
		(layer "F.Cu")
		(at -2.5146 -127.7112 -90)
		(property "Reference" "R1B10"
			(at 0 0 270)
			(layer "F.SilkS")
			(hide yes)
			(effects
				(font
					(size 1.27 1.27)
				)
			)
		)
		(property "Value" ""
			(at 0 0 270)
			(layer "F.Fab")
			(effects
				(font
					(size 1.27 1.27)
				)
			)
		)
		(duplicate_pad_numbers_are_jumpers no)
		(fp_rect
			(start 0.2794 0.9906)
			(end -0.2794 -0.1016)
			(stroke
				(width 0)
				(type default)
			)
			(fill no)
			(layer "F.CrtYd")
		)
		(fp_line
			(start -0.2794 0.9906)
			(end 0.2794 0.9906)
			(stroke
				(width 0.1)
				(type default)
			)
			(layer "F.Fab")
		)
		(fp_line
			(start 0.2794 0.9906)
			(end 0.2794 -0.1016)
			(stroke
				(width 0.1)
				(type default)
			)
			(layer "F.Fab")
		)
		(fp_line
			(start -0.2794 -0.1016)
			(end -0.2794 0.9906)
			(stroke
				(width 0.1)
				(type default)
			)
			(layer "F.Fab")
		)
		(fp_line
			(start 0.2794 -0.1016)
			(end -0.2794 -0.1016)
			(stroke
				(width 0.1)
				(type default)
			)
			(layer "F.Fab")
		)
		(pad "1" smd rect
			(at 0 0 270)
			(size 0.508 0.508)
			(layers "F.Cu" "F.Mask" "F.Paste")
			(net "SVID_VDIO_PVDDQ_KLM")
		)
		(pad "2" smd rect
			(at 0 0.889 270)
			(size 0.508 0.508)
			(layers "F.Cu" "F.Mask" "F.Paste")
			(net "SVID_DIO1_CPU1_R")
		)
		(zone
			(layer "F.Cu")
			(hatch none 0.5)
			(connect_pads
				(clearance 0)
			)
			(min_thickness 0.25)
			(keepout
				(tracks allowed)
				(vias not_allowed)
				(pads allowed)
				(copperpour not_allowed)
				(footprints allowed)
			)
			(placement
				(enabled no)
				(sheetname "")
			)
			(fill
				(thermal_gap 0.5)
				(thermal_bridge_width 0.5)
				(island_removal_mode 0)
			)
			(polygon
				(pts
					(xy -3.1496 -127.4572) (xy -2.7686 -127.4572) (xy -2.7686 -127.9652) (xy -3.1496 -127.9652)
				)
			)
		)
		(zone
			(layer "F.Cu")
			(hatch none 0.5)
			(connect_pads
				(clearance 0)
			)
			(min_thickness 0.25)
			(keepout
				(tracks not_allowed)
				(vias allowed)
				(pads allowed)
				(copperpour not_allowed)
				(footprints allowed)
			)
			(placement
				(enabled no)
				(sheetname "")
			)
			(fill
				(thermal_gap 0.5)
				(thermal_bridge_width 0.5)
				(island_removal_mode 0)
			)
			(polygon
				(pts
					(xy -3.1496 -127.4572) (xy -2.7686 -127.4572) (xy -2.7686 -127.9652) (xy -3.1496 -127.9652)
				)
			)
		)
	)
	(footprint ""
		(layer "F.Cu")
		(at 272.861532 -149.8092 90)
		(property "Reference" "C5A8"
			(at 1.848866 0.752348 90)
			(unlocked yes)
			(layer "F.SilkS")
			(effects
				(font
					(size 1.27 0.9652)
					(thickness 0.1524)
				)
			)
		)
		(property "Value" ""
			(at 0 0 90)
			(layer "F.Fab")
			(effects
				(font
					(size 1.27 1.27)
				)
			)
		)
		(duplicate_pad_numbers_are_jumpers no)
		(fp_rect
			(start -0.500126 1.598422)
			(end 0.500126 -0.201422)
			(stroke
				(width 0)
				(type default)
			)
			(fill no)
			(layer "F.CrtYd")
		)
		(fp_line
			(start 0.500126 -0.201422)
			(end 0.500126 1.598422)
			(stroke
				(width 0.1)
				(type default)
			)
			(layer "F.Fab")
		)
		(fp_line
			(start -0.500126 -0.201422)
			(end 0.500126 -0.201422)
			(stroke
				(width 0.1)
				(type default)
			)
			(layer "F.Fab")
		)
		(fp_line
			(start 0.500126 1.598422)
			(end -0.500126 1.598422)
			(stroke
				(width 0.1)
				(type default)
			)
			(layer "F.Fab")
		)
		(fp_line
			(start -0.500126 1.598422)
			(end -0.500126 -0.201422)
			(stroke
				(width 0.1)
				(type default)
			)
			(layer "F.Fab")
		)
		(pad "1" smd rect
			(at 0 0)
			(size 0.889 0.9906)
			(layers "F.Cu" "F.Mask" "F.Paste")
			(net "PVDDQ_DEF")
		)
		(pad "2" smd rect
			(at 0 1.397)
			(size 0.889 0.9906)
			(layers "F.Cu" "F.Mask" "F.Paste")
			(net "GND")
		)
		(zone
			(layer "F.Cu")
			(hatch none 0.5)
			(connect_pads
				(clearance 0)
			)
			(min_thickness 0.25)
			(keepout
				(tracks allowed)
				(vias not_allowed)
				(pads allowed)
				(copperpour not_allowed)
				(footprints allowed)
			)
			(placement
				(enabled no)
				(sheetname "")
			)
			(fill
				(thermal_gap 0.5)
				(thermal_bridge_width 0.5)
				(island_removal_mode 0)
			)
			(polygon
				(pts
					(xy 273.814032 -149.3139) (xy 273.814032 -150.3045) (xy 273.306032 -150.3045) (xy 273.306032 -149.3139)
				)
			)
		)
		(zone
			(layer "F.Cu")
			(hatch none 0.5)
			(connect_pads
				(clearance 0)
			)
			(min_thickness 0.25)
			(keepout
				(tracks not_allowed)
				(vias allowed)
				(pads allowed)
				(copperpour not_allowed)
				(footprints allowed)
			)
			(placement
				(enabled no)
				(sheetname "")
			)
			(fill
				(thermal_gap 0.5)
				(thermal_bridge_width 0.5)
				(island_removal_mode 0)
			)
			(polygon
				(pts
					(xy 273.814032 -149.3139) (xy 273.814032 -150.3045) (xy 273.306032 -150.3045) (xy 273.306032 -149.3139)
				)
			)
		)
	)
	(footprint ""
		(layer "F.Cu")
		(at 201.396346 -52.7304 -90)
		(property "Reference" "RT2"
			(at 0 0 270)
			(layer "F.SilkS")
			(hide yes)
			(effects
				(font
					(size 1.27 1.27)
				)
			)
		)
		(property "Value" "*"
			(at -0.0254 -2.6289 270)
			(unlocked yes)
			(layer "F.Fab")
			(hide yes)
			(effects
				(font
					(size 1.27 1.016)
					(thickness 0.1524)
				)
			)
		)
		(property "Device Type" "1R3F-GP_RCL_GP-1R3F-GP,64.1R00A"
			(at -0.0254 -4.1529 270)
			(unlocked yes)
			(layer "F.Fab")
			(hide yes)
			(effects
				(font
					(size 1.27 1.016)
					(thickness 0.1524)
				)
			)
		)
		(duplicate_pad_numbers_are_jumpers no)
		(fp_line
			(start -0.4826 0)
			(end -0.2032 0)
			(stroke
				(width 0.2032)
				(type default)
			)
			(layer "F.SilkS")
		)
		(fp_line
			(start 0.2032 0)
			(end 0.4826 0)
			(stroke
				(width 0.2032)
				(type default)
			)
			(layer "F.SilkS")
		)
		(fp_rect
			(start -0.5842 1.3335)
			(end 0.5842 -1.3335)
			(stroke
				(width 0)
				(type default)
			)
			(fill no)
			(layer "F.CrtYd")
		)
		(fp_rect
			(start -0.5842 1.3335)
			(end 0.5842 -1.3335)
			(stroke
				(width 0)
				(type default)
			)
			(fill no)
			(layer "F.Fab")
		)
		(pad "1" smd custom
			(at 0 -0.762 270)
			(size 0.2159 0.2159)
			(layers "F.Cu" "F.Mask" "F.Paste")
			(net "VR_PVCCIN_CPU0_PHASE1_RC")
			(options
				(clearance outline)
				(anchor circle)
			)
			(primitives
				(gr_poly
					(pts
						(arc
							(start -0.3302 -0.4318)
							(mid -0.402042 -0.402042)
							(end -0.4318 -0.3302)
						)
						(arc
							(start -0.4318 0.3302)
							(mid -0.402042 0.402042)
							(end -0.3302 0.4318)
						)
						(arc
							(start 0.3302 0.4318)
							(mid 0.402042 0.402042)
							(end 0.4318 0.3302)
						)
						(arc
							(start 0.4318 -0.3302)
							(mid 0.402042 -0.402042)
							(end 0.3302 -0.4318)
						)
					)
					(width 0)
					(fill yes)
				)
			)
		)
		(pad "2" smd custom
			(at 0 0.762 270)
			(size 0.2159 0.2159)
			(layers "F.Cu" "F.Mask" "F.Paste")
			(net "GND")
			(options
				(clearance outline)
				(anchor circle)
			)
			(primitives
				(gr_poly
					(pts
						(arc
							(start -0.3302 -0.4318)
							(mid -0.402042 -0.402042)
							(end -0.4318 -0.3302)
						)
						(arc
							(start -0.4318 0.3302)
							(mid -0.402042 0.402042)
							(end -0.3302 0.4318)
						)
						(arc
							(start 0.3302 0.4318)
							(mid 0.402042 0.402042)
							(end 0.4318 0.3302)
						)
						(arc
							(start 0.4318 -0.3302)
							(mid 0.402042 -0.402042)
							(end 0.3302 -0.4318)
						)
					)
					(width 0)
					(fill yes)
				)
			)
		)
	)
)
